(kicad_pcb
	(version 20260206)
	(generator "pcbnew")
	(generator_version "10.0")
	(general
		(thickness 1.6)
		(legacy_teardrops no)
	)
	(paper "A4")
	(title_block
		(title "netronome-mezz — pcbd0082-001_rev01_jul9_a.brd")
		(comment 1 "Open CloudServer (Microsoft) / footprints 713-714 of 714")
	)
	(layers
		(0 "F.Cu" signal "TOP")
		(4 "In1.Cu" signal "02_GND")
		(6 "In2.Cu" signal "03_SIG")
		(8 "In3.Cu" signal "04_SIG")
		(10 "In4.Cu" signal "05_GND")
		(12 "In5.Cu" signal "06_PWR1")
		(14 "In6.Cu" signal "07_SIG")
		(16 "In7.Cu" signal "08_SIG")
		(18 "In8.Cu" signal "09_GND")
		(2 "B.Cu" signal "BOTTOM")
		(9 "F.Adhes" user "F.Adhesive")
		(11 "B.Adhes" user "B.Adhesive")
		(13 "F.Paste" user "Package Geometry/Pastemask Top")
		(15 "B.Paste" user "Package Geometry/Pastemask Bottom")
		(5 "F.SilkS" user "Ref Des/Silkscreen Top")
		(7 "B.SilkS" user "Ref Des/Silkscreen Bottom")
		(1 "F.Mask" user "Board Geometry/Soldermask Top")
		(3 "B.Mask" user "Board Geometry/Soldermask Bottom")
		(17 "Dwgs.User" user "User.Drawings")
		(19 "Cmts.User" user "User.Comments")
		(21 "Eco1.User" user "User.Eco1")
		(23 "Eco2.User" user "User.Eco2")
		(25 "Edge.Cuts" user "Board Geometry/Outline")
		(27 "Margin" user)
		(31 "F.CrtYd" user "Package Geometry/Place Bound Top")
		(29 "B.CrtYd" user "Package Geometry/Place Bound Bottom")
		(35 "F.Fab" user "Ref Des/Assembly Top")
		(33 "B.Fab" user "Ref Des/Assembly Bottom")
		(45 "User.4" user "COMPVAL_TYPE_BOTTOM")
	)
	(footprint ""
		(layer "B.Cu")
		(at 76.251003 1.899006)
		(property "Reference" "V_A-DQ01"
			(at 0 0 0)
			(layer "B.SilkS")
			(hide yes)
			(effects
				(font
					(size 1.27 1.27)
				)
				(justify mirror)
			)
		)
		(property "Value" ""
			(at 0 0 0)
			(layer "B.Fab")
			(effects
				(font
					(size 1.27 1.27)
				)
				(justify mirror)
			)
		)
		(duplicate_pad_numbers_are_jumpers no)
		(pad "1" thru_hole circle
			(at 0 0 180)
			(size 0.4572 0.4572)
			(drill 0.20574)
			(layers "*.Cu" "*.Mask")
			(remove_unused_layers no)
			(net "DDR0_32A_DQ1")
			(clearance 0.1143)
			(thermal_gap 0.1143)
		)
	)
	(footprint ""
		(layer "B.Cu")
		(at 61.736986 25.041987 90)
		(property "Reference" "R186"
			(at 0.885317 -0.141986 0)
			(unlocked yes)
			(layer "B.SilkS")
			(effects
				(font
					(size 0.7874 0.5842)
					(thickness 0.127)
				)
				(justify mirror)
			)
		)
		(property "Value" ""
			(at 0 0 90)
			(layer "B.Fab")
			(effects
				(font
					(size 1.27 1.27)
				)
				(justify mirror)
			)
		)
		(duplicate_pad_numbers_are_jumpers no)
		(fp_circle
			(center 0 0)
			(end 0 0.104648)
			(stroke
				(width 0.1016)
				(type default)
			)
			(fill no)
			(layer "B.SilkS")
		)
		(fp_poly
			(pts
				(xy 0.381 -0.889) (xy 0.381 0.889) (xy -0.381 0.889) (xy -0.381 -0.889)
			)
			(stroke
				(width 0)
				(type default)
			)
			(fill no)
			(layer "B.CrtYd")
		)
		(fp_line
			(start 0.508 -1.016)
			(end 0.254 -1.016)
			(stroke
				(width 0.0254)
				(type default)
			)
			(layer "B.Fab")
		)
		(fp_line
			(start 0.254 -1.016)
			(end -0.508 -1.016)
			(stroke
				(width 0.0254)
				(type default)
			)
			(layer "B.Fab")
		)
		(fp_line
			(start -0.508 -1.016)
			(end -0.508 1.016)
			(stroke
				(width 0.0254)
				(type default)
			)
			(layer "B.Fab")
		)
		(fp_line
			(start 0.508 1.016)
			(end 0.508 -1.016)
			(stroke
				(width 0.0254)
				(type default)
			)
			(layer "B.Fab")
		)
		(fp_line
			(start -0.508 1.016)
			(end 0.508 1.016)
			(stroke
				(width 0.0254)
				(type default)
			)
			(layer "B.Fab")
		)
		(pad "1" smd custom
			(at 0 -0.500126 270)
			(size 0.127 0.127)
			(layers "B.Cu" "B.Mask" "B.Paste")
			(net "GND")
			(options
				(clearance outline)
				(anchor circle)
			)
			(primitives
				(gr_poly
					(pts
						(xy -0.1778 0.254) (xy 0.1778 0.254) (xy 0.254 0.1778) (xy 0.254 -0.1778) (xy 0.1778 -0.254) (xy -0.1778 -0.254)
						(xy -0.254 -0.1778) (xy -0.254 0.1778)
					)
					(width 0)
					(fill yes)
				)
			)
		)
		(pad "2" smd custom
			(at 0 0.500126 270)
			(size 0.127 0.127)
			(layers "B.Cu" "B.Mask" "B.Paste")
			(net "A_DZQ1")
			(options
				(clearance outline)
				(anchor circle)
			)
			(primitives
				(gr_poly
					(pts
						(xy -0.1778 0.254) (xy 0.1778 0.254) (xy 0.254 0.1778) (xy 0.254 -0.1778) (xy 0.1778 -0.254) (xy -0.1778 -0.254)
						(xy -0.254 -0.1778) (xy -0.254 0.1778)
					)
					(width 0)
					(fill yes)
				)
			)
		)
	)
)
